(kicad_pcb
	(version 20241229)
	(generator "pcbnew")
	(generator_version "9.0")
	(general
		(thickness 1.6)
		(legacy_teardrops no)
	)
	(paper "A4")
	(title_block
		(title "OCuLink to PCIe adapter")
		(date "2025-06-18")
		(rev "1.0.0")
		(company "Antmicro Ltd")
		(comment 1 "www.antmicro.com")
		(comment 9 "footprint 156 of 159 (J2), pads 1-87 of 168")
	)
	(layers
		(0 "F.Cu" signal)
		(4 "In1.Cu" signal)
		(6 "In2.Cu" signal)
		(2 "B.Cu" signal)
		(9 "F.Adhes" user "F.Adhesive")
		(11 "B.Adhes" user "B.Adhesive")
		(13 "F.Paste" user)
		(15 "B.Paste" user)
		(5 "F.SilkS" user "F.Silkscreen")
		(7 "B.SilkS" user "B.Silkscreen")
		(1 "F.Mask" user)
		(3 "B.Mask" user)
		(17 "Dwgs.User" user "User.Drawings")
		(19 "Cmts.User" user "User.Comments")
		(21 "Eco1.User" user "User.Eco1")
		(23 "Eco2.User" user "User.Eco2")
		(25 "Edge.Cuts" user)
		(27 "Margin" user)
		(31 "F.CrtYd" user "F.Courtyard")
		(29 "B.CrtYd" user "B.Courtyard")
		(35 "F.Fab" user)
		(33 "B.Fab" user)
	)
	(footprint "antmicro-footprints:AMPHENOL_10146070-113Y0LF"
		(locked yes)
		(layer "F.Cu")
		(at 111.674 79.6 90)
		(property "Reference" "J2"
			(at 41.1 5.926 90)
			(layer "F.SilkS")
			(effects
				(font
					(size 0.7 0.7)
					(thickness 0.15)
				)
				(justify left bottom)
			)
		)
		(property "Value" "PCIe_x16_10146070-113Y0LF-vertical"
			(at -28.471 6.61 90)
			(layer "F.Fab")
			(effects
				(font
					(size 0.7 0.7)
					(thickness 0.15)
				)
				(justify left bottom)
			)
		)
		(property "Datasheet" "https://www.farnell.com/datasheets/3212936.pdf"
			(at 0 0 90)
			(layer "F.Fab")
			(hide yes)
			(effects
				(font
					(size 1.27 1.27)
					(thickness 0.15)
				)
			)
		)
		(property "Description" "164 Position Female Connector PCI Express™ Gold 0.039\" (1.00mm) Black"
			(at 0 0 90)
			(layer "F.Fab")
			(hide yes)
			(effects
				(font
					(size 1.27 1.27)
					(thickness 0.15)
				)
			)
		)
		(property "PARTREV" "E"
			(at 0 0 90)
			(unlocked yes)
			(layer "F.Fab")
			(hide yes)
			(effects
				(font
					(size 1 1)
					(thickness 0.15)
				)
			)
		)
		(property "STANDARD" "Manufacturer Recommendations"
			(at 0 0 90)
			(unlocked yes)
			(layer "F.Fab")
			(hide yes)
			(effects
				(font
					(size 1 1)
					(thickness 0.15)
				)
			)
		)
		(property "MAXIMUM_PACKAGE_HEIGHT" "11.25mm"
			(at 0 0 90)
			(unlocked yes)
			(layer "F.Fab")
			(hide yes)
			(effects
				(font
					(size 1 1)
					(thickness 0.15)
				)
			)
		)
		(property "Manufacturer" "Amphenol"
			(at 0 0 90)
			(unlocked yes)
			(layer "F.Fab")
			(hide yes)
			(effects
				(font
					(size 1 1)
					(thickness 0.15)
				)
			)
		)
		(property "Author" "Antmicro"
			(at 0 0 90)
			(unlocked yes)
			(layer "F.Fab")
			(hide yes)
			(effects
				(font
					(size 1 1)
					(thickness 0.15)
				)
			)
		)
		(property "License" "Apache-2.0"
			(at 0 0 90)
			(unlocked yes)
			(layer "F.Fab")
			(hide yes)
			(effects
				(font
					(size 1 1)
					(thickness 0.15)
				)
			)
		)
		(property "MPN" "10146070-113Y0LF"
			(at 0 0 90)
			(unlocked yes)
			(layer "F.Fab")
			(hide yes)
			(effects
				(font
					(size 1 1)
					(thickness 0.15)
				)
			)
		)
		(sheetname "/PCIe-connector/")
		(sheetfile "pcie-connector.kicad_sch")
		(attr smd)
		(pad "" np_thru_hole circle
			(at -29.851 -0.5 90)
			(size 1.25 1.25)
			(drill 1.25)
			(layers "*.Cu" "*.Mask")
		)
		(pad "" np_thru_hole circle
			(at 43.298 -0.5 90)
			(size 1.25 1.25)
			(drill 1.25)
			(layers "*.Cu" "*.Mask")
		)
		(pad "A1" smd rect
			(at -41.5 -4.1 90)
			(size 0.53 2)
			(layers "F.Cu" "F.Mask" "F.Paste")
			(net 55 "unconnected-(J2-PadA1)")
			(pinfunction "A1")
			(pintype "passive+no_connect")
		)
		(pad "A2" smd rect
			(at -40.5 -4.1 90)
			(size 0.53 2)
			(layers "F.Cu" "F.Mask" "F.Paste")
			(net 87 "+12V")
			(pinfunction "A2")
			(pintype "passive")
		)
		(pad "A3" smd rect
			(at -39.5 -4.1 90)
			(size 0.53 2)
			(layers "F.Cu" "F.Mask" "F.Paste")
			(net 87 "+12V")
			(pinfunction "A3")
			(pintype "passive")
		)
		(pad "A4" smd rect
			(at -38.5 -4.1 90)
			(size 0.53 2)
			(layers "F.Cu" "F.Mask" "F.Paste")
			(net 66 "GND")
			(pinfunction "A4")
			(pintype "passive")
		)
		(pad "A5" smd rect
			(at -37.5 -4.1 90)
			(size 0.53 2)
			(layers "F.Cu" "F.Mask" "F.Paste")
			(net 24 "unconnected-(J2-PadA5)")
			(pinfunction "A5")
			(pintype "passive+no_connect")
		)
		(pad "A6" smd rect
			(at -36.5 -4.1 90)
			(size 0.53 2)
			(layers "F.Cu" "F.Mask" "F.Paste")
			(net 19 "unconnected-(J2-PadA6)")
			(pinfunction "A6")
			(pintype "passive+no_connect")
		)
		(pad "A7" smd rect
			(at -35.5 -4.1 90)
			(size 0.53 2)
			(layers "F.Cu" "F.Mask" "F.Paste")
			(net 57 "unconnected-(J2-PadA7)")
			(pinfunction "A7")
			(pintype "passive+no_connect")
		)
		(pad "A8" smd rect
			(at -34.5 -4.1 90)
			(size 0.53 2)
			(layers "F.Cu" "F.Mask" "F.Paste")
			(net 21 "unconnected-(J2-PadA8)")
			(pinfunction "A8")
			(pintype "passive+no_connect")
		)
		(pad "A9" smd rect
			(at -33.5 -4.1 90)
			(size 0.53 2)
			(layers "F.Cu" "F.Mask" "F.Paste")
			(net 134 "+3V3")
			(pinfunction "A9")
			(pintype "passive")
		)
		(pad "A10" smd rect
			(at -32.5 -4.1 90)
			(size 0.53 2)
			(layers "F.Cu" "F.Mask" "F.Paste")
			(net 134 "+3V3")
			(pinfunction "A10")
			(pintype "passive")
		)
		(pad "A11" smd rect
			(at -31.5 -4.1 90)
			(size 0.53 2)
			(layers "F.Cu" "F.Mask" "F.Paste")
			(net 172 "/Power/~{PERST}")
			(pinfunction "A11")
			(pintype "passive")
		)
		(pad "A12" smd rect
			(at -28.5 -4.1 90)
			(size 0.53 2)
			(layers "F.Cu" "F.Mask" "F.Paste")
			(net 66 "GND")
			(pinfunction "A12")
			(pintype "passive")
		)
		(pad "A13" smd rect
			(at -27.5 -4.1 90)
			(size 0.53 2)
			(layers "F.Cu" "F.Mask" "F.Paste")
			(net 96 "/OCuLink/PCIe_{REF0}.CK+")
			(pinfunction "A13")
			(pintype "passive")
		)
		(pad "A14" smd rect
			(at -26.5 -4.1 90)
			(size 0.53 2)
			(layers "F.Cu" "F.Mask" "F.Paste")
			(net 97 "/OCuLink/PCIe_{REF0}.CK-")
			(pinfunction "A14")
			(pintype "passive")
		)
		(pad "A15" smd rect
			(at -25.5 -4.1 90)
			(size 0.53 2)
			(layers "F.Cu" "F.Mask" "F.Paste")
			(net 66 "GND")
			(pinfunction "A15")
			(pintype "passive")
		)
		(pad "A16" smd rect
			(at -24.5 -4.1 90)
			(size 0.53 2)
			(layers "F.Cu" "F.Mask" "F.Paste")
			(net 78 "/OCuLink/PCIe_{x4}.RX0+")
			(pinfunction "A16")
			(pintype "passive")
		)
		(pad "A17" smd rect
			(at -23.5 -4.1 90)
			(size 0.53 2)
			(layers "F.Cu" "F.Mask" "F.Paste")
			(net 73 "/OCuLink/PCIe_{x4}.RX0-")
			(pinfunction "A17")
			(pintype "passive")
		)
		(pad "A18" smd rect
			(at -22.5 -4.1 90)
			(size 0.53 2)
			(layers "F.Cu" "F.Mask" "F.Paste")
			(net 66 "GND")
			(pinfunction "A18")
			(pintype "passive")
		)
		(pad "A19" smd rect
			(at -21.5 -4.1 90)
			(size 0.53 2)
			(layers "F.Cu" "F.Mask" "F.Paste")
			(net 36 "unconnected-(J2-PadA19)")
			(pinfunction "A19")
			(pintype "passive+no_connect")
		)
		(pad "A20" smd rect
			(at -20.5 -4.1 90)
			(size 0.53 2)
			(layers "F.Cu" "F.Mask" "F.Paste")
			(net 66 "GND")
			(pinfunction "A20")
			(pintype "passive")
		)
		(pad "A21" smd rect
			(at -19.5 -4.1 90)
			(size 0.53 2)
			(layers "F.Cu" "F.Mask" "F.Paste")
			(net 75 "/OCuLink/PCIe_{x4}.RX1+")
			(pinfunction "A21")
			(pintype "passive")
		)
		(pad "A22" smd rect
			(at -18.5 -4.1 90)
			(size 0.53 2)
			(layers "F.Cu" "F.Mask" "F.Paste")
			(net 71 "/OCuLink/PCIe_{x4}.RX1-")
			(pinfunction "A22")
			(pintype "passive")
		)
		(pad "A23" smd rect
			(at -17.5 -4.1 90)
			(size 0.53 2)
			(layers "F.Cu" "F.Mask" "F.Paste")
			(net 66 "GND")
			(pinfunction "A23")
			(pintype "passive")
		)
		(pad "A24" smd rect
			(at -16.5 -4.1 90)
			(size 0.53 2)
			(layers "F.Cu" "F.Mask" "F.Paste")
			(net 66 "GND")
			(pinfunction "A24")
			(pintype "passive")
		)
		(pad "A25" smd rect
			(at -15.501 -4.1 90)
			(size 0.53 2)
			(layers "F.Cu" "F.Mask" "F.Paste")
			(net 81 "/OCuLink/PCIe_{x4}.RX2+")
			(pinfunction "A25")
			(pintype "passive")
		)
		(pad "A26" smd rect
			(at -14.501 -4.1 90)
			(size 0.53 2)
			(layers "F.Cu" "F.Mask" "F.Paste")
			(net 79 "/OCuLink/PCIe_{x4}.RX2-")
			(pinfunction "A26")
			(pintype "passive")
		)
		(pad "A27" smd rect
			(at -13.501 -4.1 90)
			(size 0.53 2)
			(layers "F.Cu" "F.Mask" "F.Paste")
			(net 66 "GND")
			(pinfunction "A27")
			(pintype "passive")
		)
		(pad "A28" smd rect
			(at -12.501 -4.1 90)
			(size 0.53 2)
			(layers "F.Cu" "F.Mask" "F.Paste")
			(net 66 "GND")
			(pinfunction "A28")
			(pintype "passive")
		)
		(pad "A29" smd rect
			(at -11.501 -4.1 90)
			(size 0.53 2)
			(layers "F.Cu" "F.Mask" "F.Paste")
			(net 68 "/OCuLink/PCIe_{x4}.RX3+")
			(pinfunction "A29")
			(pintype "passive")
		)
		(pad "A30" smd rect
			(at -10.501 -4.1 90)
			(size 0.53 2)
			(layers "F.Cu" "F.Mask" "F.Paste")
			(net 67 "/OCuLink/PCIe_{x4}.RX3-")
			(pinfunction "A30")
			(pintype "passive")
		)
		(pad "A31" smd rect
			(at -9.501 -4.1 90)
			(size 0.53 2)
			(layers "F.Cu" "F.Mask" "F.Paste")
			(net 66 "GND")
			(pinfunction "A31")
			(pintype "passive")
		)
		(pad "A32" smd rect
			(at -8.501 -4.1 90)
			(size 0.53 2)
			(layers "F.Cu" "F.Mask" "F.Paste")
			(net 27 "unconnected-(J2-PadA32)")
			(pinfunction "A32")
			(pintype "passive+no_connect")
		)
		(pad "A33" smd rect
			(at -7.502 -4.1 90)
			(size 0.53 2)
			(layers "F.Cu" "F.Mask" "F.Paste")
			(net 49 "unconnected-(J2-PadA33)")
			(pinfunction "A33")
			(pintype "passive+no_connect")
		)
		(pad "A34" smd rect
			(at -6.502 -4.1 90)
			(size 0.53 2)
			(layers "F.Cu" "F.Mask" "F.Paste")
			(net 66 "GND")
			(pinfunction "A34")
			(pintype "passive")
		)
		(pad "A35" smd rect
			(at -5.502 -4.1 90)
			(size 0.53 2)
			(layers "F.Cu" "F.Mask" "F.Paste")
			(net 62 "unconnected-(J2-PadA35)")
			(pinfunction "A35")
			(pintype "passive+no_connect")
		)
		(pad "A36" smd rect
			(at -4.502 -4.1 90)
			(size 0.53 2)
			(layers "F.Cu" "F.Mask" "F.Paste")
			(net 1 "unconnected-(J2-PadA36)")
			(pinfunction "A36")
			(pintype "passive+no_connect")
		)
		(pad "A37" smd rect
			(at -3.501 -4.1 90)
			(size 0.53 2)
			(layers "F.Cu" "F.Mask" "F.Paste")
			(net 66 "GND")
			(pinfunction "A37")
			(pintype "passive")
		)
		(pad "A38" smd rect
			(at -2.501 -4.1 90)
			(size 0.53 2)
			(layers "F.Cu" "F.Mask" "F.Paste")
			(net 66 "GND")
			(pinfunction "A38")
			(pintype "passive")
		)
		(pad "A39" smd rect
			(at -1.502 -4.1 90)
			(size 0.53 2)
			(layers "F.Cu" "F.Mask" "F.Paste")
			(net 14 "unconnected-(J2-PadA39)")
			(pinfunction "A39")
			(pintype "passive+no_connect")
		)
		(pad "A40" smd rect
			(at -0.501 -4.1 90)
			(size 0.53 2)
			(layers "F.Cu" "F.Mask" "F.Paste")
			(net 64 "unconnected-(J2-PadA40)")
			(pinfunction "A40")
			(pintype "passive+no_connect")
		)
		(pad "A41" smd rect
			(at 0.498 -4.1 90)
			(size 0.53 2)
			(layers "F.Cu" "F.Mask" "F.Paste")
			(net 66 "GND")
			(pinfunction "A41")
			(pintype "passive")
		)
		(pad "A42" smd rect
			(at 1.499 -4.1 90)
			(size 0.53 2)
			(layers "F.Cu" "F.Mask" "F.Paste")
			(net 66 "GND")
			(pinfunction "A42")
			(pintype "passive")
		)
		(pad "A43" smd rect
			(at 2.499 -4.1 90)
			(size 0.53 2)
			(layers "F.Cu" "F.Mask" "F.Paste")
			(net 39 "unconnected-(J2-PadA43)")
			(pinfunction "A43")
			(pintype "passive+no_connect")
		)
		(pad "A44" smd rect
			(at 3.499 -4.1 90)
			(size 0.53 2)
			(layers "F.Cu" "F.Mask" "F.Paste")
			(net 53 "unconnected-(J2-PadA44)")
			(pinfunction "A44")
			(pintype "passive+no_connect")
		)
		(pad "A45" smd rect
			(at 4.498 -4.1 90)
			(size 0.53 2)
			(layers "F.Cu" "F.Mask" "F.Paste")
			(net 66 "GND")
			(pinfunction "A45")
			(pintype "passive")
		)
		(pad "A46" smd rect
			(at 5.499 -4.1 90)
			(size 0.53 2)
			(layers "F.Cu" "F.Mask" "F.Paste")
			(net 66 "GND")
			(pinfunction "A46")
			(pintype "passive")
		)
		(pad "A47" smd rect
			(at 6.499 -4.1 90)
			(size 0.53 2)
			(layers "F.Cu" "F.Mask" "F.Paste")
			(net 16 "unconnected-(J2-PadA47)")
			(pinfunction "A47")
			(pintype "passive+no_connect")
		)
		(pad "A48" smd rect
			(at 7.499 -4.1 90)
			(size 0.53 2)
			(layers "F.Cu" "F.Mask" "F.Paste")
			(net 12 "unconnected-(J2-PadA48)")
			(pinfunction "A48")
			(pintype "passive+no_connect")
		)
		(pad "A49" smd rect
			(at 8.499 -4.1 90)
			(size 0.53 2)
			(layers "F.Cu" "F.Mask" "F.Paste")
			(net 66 "GND")
			(pinfunction "A49")
			(pintype "passive")
		)
		(pad "A50" smd rect
			(at 9.499 -4.1 90)
			(size 0.53 2)
			(layers "F.Cu" "F.Mask" "F.Paste")
			(net 2 "unconnected-(J2-PadA50)")
			(pinfunction "A50")
			(pintype "passive+no_connect")
		)
		(pad "A51" smd rect
			(at 10.499 -4.1 90)
			(size 0.53 2)
			(layers "F.Cu" "F.Mask" "F.Paste")
			(net 66 "GND")
			(pinfunction "A51")
			(pintype "passive")
		)
		(pad "A52" smd rect
			(at 11.499 -4.1 90)
			(size 0.53 2)
			(layers "F.Cu" "F.Mask" "F.Paste")
			(net 26 "unconnected-(J2-PadA52)")
			(pinfunction "A52")
			(pintype "passive+no_connect")
		)
		(pad "A53" smd rect
			(at 12.499 -4.1 90)
			(size 0.53 2)
			(layers "F.Cu" "F.Mask" "F.Paste")
			(net 29 "unconnected-(J2-PadA53)")
			(pinfunction "A53")
			(pintype "passive+no_connect")
		)
		(pad "A54" smd rect
			(at 13.499 -4.1 90)
			(size 0.53 2)
			(layers "F.Cu" "F.Mask" "F.Paste")
			(net 66 "GND")
			(pinfunction "A54")
			(pintype "passive")
		)
		(pad "A55" smd rect
			(at 14.499 -4.1 90)
			(size 0.53 2)
			(layers "F.Cu" "F.Mask" "F.Paste")
			(net 66 "GND")
			(pinfunction "A55")
			(pintype "passive")
		)
		(pad "A56" smd rect
			(at 15.499 -4.1 90)
			(size 0.53 2)
			(layers "F.Cu" "F.Mask" "F.Paste")
			(net 40 "unconnected-(J2-PadA56)")
			(pinfunction "A56")
			(pintype "passive+no_connect")
		)
		(pad "A57" smd rect
			(at 16.498 -4.1 90)
			(size 0.53 2)
			(layers "F.Cu" "F.Mask" "F.Paste")
			(net 37 "unconnected-(J2-PadA57)")
			(pinfunction "A57")
			(pintype "passive+no_connect")
		)
		(pad "A58" smd rect
			(at 17.498 -4.1 90)
			(size 0.53 2)
			(layers "F.Cu" "F.Mask" "F.Paste")
			(net 66 "GND")
			(pinfunction "A58")
			(pintype "passive")
		)
		(pad "A59" smd rect
			(at 18.498 -4.1 90)
			(size 0.53 2)
			(layers "F.Cu" "F.Mask" "F.Paste")
			(net 66 "GND")
			(pinfunction "A59")
			(pintype "passive")
		)
		(pad "A60" smd rect
			(at 19.498 -4.1 90)
			(size 0.53 2)
			(layers "F.Cu" "F.Mask" "F.Paste")
			(net 18 "unconnected-(J2-PadA60)")
			(pinfunction "A60")
			(pintype "passive+no_connect")
		)
		(pad "A61" smd rect
			(at 20.498 -4.1 90)
			(size 0.53 2)
			(layers "F.Cu" "F.Mask" "F.Paste")
			(net 30 "unconnected-(J2-PadA61)")
			(pinfunction "A61")
			(pintype "passive+no_connect")
		)
		(pad "A62" smd rect
			(at 21.498 -4.1 90)
			(size 0.53 2)
			(layers "F.Cu" "F.Mask" "F.Paste")
			(net 66 "GND")
			(pinfunction "A62")
			(pintype "passive")
		)
		(pad "A63" smd rect
			(at 22.498 -4.1 90)
			(size 0.53 2)
			(layers "F.Cu" "F.Mask" "F.Paste")
			(net 66 "GND")
			(pinfunction "A63")
			(pintype "passive")
		)
		(pad "A64" smd rect
			(at 23.498 -4.1 90)
			(size 0.53 2)
			(layers "F.Cu" "F.Mask" "F.Paste")
			(net 3 "unconnected-(J2-PadA64)")
			(pinfunction "A64")
			(pintype "passive+no_connect")
		)
		(pad "A65" smd rect
			(at 24.498 -4.1 90)
			(size 0.53 2)
			(layers "F.Cu" "F.Mask" "F.Paste")
			(net 6 "unconnected-(J2-PadA65)")
			(pinfunction "A65")
			(pintype "passive+no_connect")
		)
		(pad "A66" smd rect
			(at 25.498 -4.1 90)
			(size 0.53 2)
			(layers "F.Cu" "F.Mask" "F.Paste")
			(net 66 "GND")
			(pinfunction "A66")
			(pintype "passive")
		)
		(pad "A67" smd rect
			(at 26.498 -4.1 90)
			(size 0.53 2)
			(layers "F.Cu" "F.Mask" "F.Paste")
			(net 66 "GND")
			(pinfunction "A67")
			(pintype "passive")
		)
		(pad "A68" smd rect
			(at 27.499 -4.1 90)
			(size 0.53 2)
			(layers "F.Cu" "F.Mask" "F.Paste")
			(net 23 "unconnected-(J2-PadA68)")
			(pinfunction "A68")
			(pintype "passive+no_connect")
		)
		(pad "A69" smd rect
			(at 28.499 -4.1 90)
			(size 0.53 2)
			(layers "F.Cu" "F.Mask" "F.Paste")
			(net 20 "unconnected-(J2-PadA69)")
			(pinfunction "A69")
			(pintype "passive+no_connect")
		)
		(pad "A70" smd rect
			(at 29.499 -4.1 90)
			(size 0.53 2)
			(layers "F.Cu" "F.Mask" "F.Paste")
			(net 66 "GND")
			(pinfunction "A70")
			(pintype "passive")
		)
		(pad "A71" smd rect
			(at 30.499 -4.1 90)
			(size 0.53 2)
			(layers "F.Cu" "F.Mask" "F.Paste")
			(net 66 "GND")
			(pinfunction "A71")
			(pintype "passive")
		)
		(pad "A72" smd rect
			(at 31.499 -4.1 90)
			(size 0.53 2)
			(layers "F.Cu" "F.Mask" "F.Paste")
			(net 8 "unconnected-(J2-PadA72)")
			(pinfunction "A72")
			(pintype "passive+no_connect")
		)
		(pad "A73" smd rect
			(at 32.499 -4.1 90)
			(size 0.53 2)
			(layers "F.Cu" "F.Mask" "F.Paste")
			(net 59 "unconnected-(J2-PadA73)")
			(pinfunction "A73")
			(pintype "passive+no_connect")
		)
		(pad "A74" smd rect
			(at 33.499 -4.1 90)
			(size 0.53 2)
			(layers "F.Cu" "F.Mask" "F.Paste")
			(net 66 "GND")
			(pinfunction "A74")
			(pintype "passive")
		)
		(pad "A75" smd rect
			(at 34.499 -4.1 90)
			(size 0.53 2)
			(layers "F.Cu" "F.Mask" "F.Paste")
			(net 66 "GND")
			(pinfunction "A75")
			(pintype "passive")
		)
		(pad "A76" smd rect
			(at 35.499 -4.1 90)
			(size 0.53 2)
			(layers "F.Cu" "F.Mask" "F.Paste")
			(net 13 "unconnected-(J2-PadA76)")
			(pinfunction "A76")
			(pintype "passive+no_connect")
		)
		(pad "A77" smd rect
			(at 36.499 -4.1 90)
			(size 0.53 2)
			(layers "F.Cu" "F.Mask" "F.Paste")
			(net 45 "unconnected-(J2-PadA77)")
			(pinfunction "A77")
			(pintype "passive+no_connect")
		)
		(pad "A78" smd rect
			(at 37.499 -4.1 90)
			(size 0.53 2)
			(layers "F.Cu" "F.Mask" "F.Paste")
			(net 66 "GND")
			(pinfunction "A78")
			(pintype "passive")
		)
		(pad "A79" smd rect
			(at 38.499 -4.1 90)
			(size 0.53 2)
			(layers "F.Cu" "F.Mask" "F.Paste")
			(net 66 "GND")
			(pinfunction "A79")
			(pintype "passive")
		)
		(pad "A80" smd rect
			(at 39.499 -4.1 90)
			(size 0.53 2)
			(layers "F.Cu" "F.Mask" "F.Paste")
			(net 32 "unconnected-(J2-PadA80)")
			(pinfunction "A80")
			(pintype "passive+no_connect")
		)
		(pad "A81" smd rect
			(at 40.499 -4.1 90)
			(size 0.53 2)
			(layers "F.Cu" "F.Mask" "F.Paste")
			(net 47 "unconnected-(J2-PadA81)")
			(pinfunction "A81")
			(pintype "passive+no_connect")
		)
		(pad "A82" smd rect
			(at 41.499 -4.1 90)
			(size 0.53 2)
			(layers "F.Cu" "F.Mask" "F.Paste")
			(net 66 "GND")
			(pinfunction "A82")
			(pintype "passive")
		)
		(pad "B1" smd rect
			(at -41.5 3.1 90)
			(size 0.53 2)
			(layers "F.Cu" "F.Mask" "F.Paste")
			(net 87 "+12V")
			(pinfunction "B1")
			(pintype "passive")
		)
		(pad "B2" smd rect
			(at -40.5 3.1 90)
			(size 0.53 2)
			(layers "F.Cu" "F.Mask" "F.Paste")
			(net 87 "+12V")
			(pinfunction "B2")
			(pintype "passive")
		)
		(pad "B3" smd rect
			(at -39.5 3.1 90)
			(size 0.53 2)
			(layers "F.Cu" "F.Mask" "F.Paste")
			(net 87 "+12V")
			(pinfunction "B3")
			(pintype "passive")
		)
	)
)
